(kicad_pcb
	(version 20260206)
	(generator "pcbnew")
	(generator_version "10.0")
	(general
		(thickness 1.6)
		(legacy_teardrops no)
	)
	(paper "A4")
	(title_block
		(title "Bryce Canyon_R.DPB_16317-1_OCP.brd")
		(comment 1 "Bryce Canyon / footprints 681-683 of 2099")
	)
	(layers
		(0 "F.Cu" signal "TOP")
		(4 "In1.Cu" signal "L2GND")
		(6 "In2.Cu" signal "L3")
		(8 "In3.Cu" signal "L4VCC")
		(10 "In4.Cu" signal "L5VCC")
		(12 "In5.Cu" signal "L6")
		(14 "In6.Cu" signal "L7GND")
		(2 "B.Cu" signal "BOTTOM")
		(9 "F.Adhes" user "F.Adhesive")
		(11 "B.Adhes" user "B.Adhesive")
		(13 "F.Paste" user "Package Geometry/Pastemask Top")
		(15 "B.Paste" user "Package Geometry/Pastemask Bottom")
		(5 "F.SilkS" user "Ref Des/Silkscreen Top")
		(7 "B.SilkS" user "Ref Des/Silkscreen Bottom")
		(1 "F.Mask" user "Board Geometry/Soldermask Top")
		(3 "B.Mask" user "Board Geometry/Soldermask Bottom")
		(17 "Dwgs.User" user "User.Drawings")
		(19 "Cmts.User" user "User.Comments")
		(21 "Eco1.User" user "User.Eco1")
		(23 "Eco2.User" user "User.Eco2")
		(25 "Edge.Cuts" user "Board Geometry/Outline")
		(27 "Margin" user)
		(31 "F.CrtYd" user "Package Geometry/Place Bound Top")
		(29 "B.CrtYd" user "Package Geometry/Place Bound Bottom")
		(35 "F.Fab" user "Ref Des/Assembly Top")
		(33 "B.Fab" user "Ref Des/Assembly Bottom")
	)
	(footprint ""
		(layer "F.Cu")
		(at 350.942402 -244.889274 90)
		(property "Reference" "VIA15"
			(at 0 0 90)
			(layer "F.SilkS")
			(hide yes)
			(effects
				(font
					(size 1.27 1.27)
				)
			)
		)
		(property "Value" "100OHM-8L-2D36MM-L18-GP"
			(at 3.8989 0.5715 90)
			(unlocked yes)
			(layer "F.Fab")
			(hide yes)
			(effects
				(font
					(size 1.016 1.016)
					(thickness 0.1524)
				)
			)
		)
		(property "Device Type" "VIA-PCIE-4P-414097"
			(at 3.8989 -0.9525 90)
			(unlocked yes)
			(layer "F.Fab")
			(hide yes)
			(effects
				(font
					(size 1.016 1.016)
					(thickness 0.1524)
				)
			)
		)
		(duplicate_pad_numbers_are_jumpers no)
		(fp_rect
			(start -2.0701 0.4826)
			(end 2.0701 -0.4826)
			(stroke
				(width 0)
				(type default)
			)
			(fill no)
			(layer "F.CrtYd")
		)
		(fp_rect
			(start -2.0701 0.4826)
			(end 2.0701 -0.4826)
			(stroke
				(width 0)
				(type default)
			)
			(fill no)
			(layer "F.Fab")
		)
		(pad "1" thru_hole circle
			(at -1.5875 0 90)
			(size 0.508 0.508)
			(drill 0.254)
			(layers "*.Cu" "*.Mask")
			(remove_unused_layers no)
			(net "GND")
			(clearance 0.2286)
			(thermal_gap 0.2286)
		)
		(pad "2" thru_hole circle
			(at -0.5715 0 90)
			(size 0.508 0.508)
			(drill 0.254)
			(layers "*.Cu" "*.Mask")
			(remove_unused_layers no)
			(net "PHY_SCC_B_TO_DRV_B_7_DP")
			(clearance 0.2286)
			(thermal_gap 0.2286)
		)
		(pad "3" thru_hole circle
			(at 0.5715 0 90)
			(size 0.508 0.508)
			(drill 0.254)
			(layers "*.Cu" "*.Mask")
			(remove_unused_layers no)
			(net "PHY_SCC_B_TO_DRV_B_7_DN")
			(clearance 0.2286)
			(thermal_gap 0.2286)
		)
		(pad "4" thru_hole circle
			(at 1.5875 0 90)
			(size 0.508 0.508)
			(drill 0.254)
			(layers "*.Cu" "*.Mask")
			(remove_unused_layers no)
			(net "GND")
			(clearance 0.2286)
			(thermal_gap 0.2286)
		)
	)
	(footprint ""
		(layer "F.Cu")
		(at 141.097 -140.462 90)
		(property "Reference" "C247"
			(at 0 0 90)
			(layer "F.SilkS")
			(hide yes)
			(effects
				(font
					(size 1.27 1.27)
				)
			)
		)
		(property "Value" "SCD033U25V2KX-GP"
			(at 1.1811 -2.7051 90)
			(unlocked yes)
			(layer "F.Fab")
			(hide yes)
			(effects
				(font
					(size 1.016 1.016)
					(thickness 0.1524)
				)
			)
		)
		(property "Device Type" "C402H22"
			(at 1.1811 -4.2291 90)
			(unlocked yes)
			(layer "F.Fab")
			(hide yes)
			(effects
				(font
					(size 1.016 1.016)
					(thickness 0.1524)
				)
			)
		)
		(duplicate_pad_numbers_are_jumpers no)
		(fp_rect
			(start -0.4318 0.9525)
			(end 0.4318 -0.9525)
			(stroke
				(width 0)
				(type default)
			)
			(fill no)
			(layer "F.CrtYd")
		)
		(fp_rect
			(start -0.4318 0.9525)
			(end 0.4318 -0.9525)
			(stroke
				(width 0)
				(type default)
			)
			(fill no)
			(layer "F.Fab")
		)
		(pad "1" smd custom
			(at 0 -0.4445 90)
			(size 0.1524 0.1524)
			(layers "F.Cu" "F.Mask" "F.Paste")
			(net "P12V_B")
			(options
				(clearance outline)
				(anchor circle)
			)
			(primitives
				(gr_poly
					(pts
						(arc
							(start 0.3048 -0.2032)
							(mid 0.275042 -0.275042)
							(end 0.2032 -0.3048)
						)
						(arc
							(start -0.2032 -0.3048)
							(mid -0.275042 -0.275042)
							(end -0.3048 -0.2032)
						)
						(arc
							(start -0.3048 0.2032)
							(mid -0.275042 0.275042)
							(end -0.2032 0.3048)
						)
						(arc
							(start 0.2032 0.3048)
							(mid 0.275042 0.275042)
							(end 0.3048 0.2032)
						)
					)
					(width 0)
					(fill yes)
				)
			)
		)
		(pad "2" smd custom
			(at 0 0.4445 90)
			(size 0.1524 0.1524)
			(layers "F.Cu" "F.Mask" "F.Paste")
			(net "SW_HDD_N16")
			(options
				(clearance outline)
				(anchor circle)
			)
			(primitives
				(gr_poly
					(pts
						(arc
							(start 0.3048 -0.2032)
							(mid 0.275042 -0.275042)
							(end 0.2032 -0.3048)
						)
						(arc
							(start -0.2032 -0.3048)
							(mid -0.275042 -0.275042)
							(end -0.3048 -0.2032)
						)
						(arc
							(start -0.3048 0.2032)
							(mid -0.275042 0.275042)
							(end -0.2032 0.3048)
						)
						(arc
							(start 0.2032 0.3048)
							(mid 0.275042 0.275042)
							(end 0.3048 0.2032)
						)
					)
					(width 0)
					(fill yes)
				)
			)
		)
	)
	(footprint ""
		(layer "F.Cu")
		(at 431.419 -263.017)
		(property "Reference" "Q36"
			(at 0 0 0)
			(layer "F.SilkS")
			(hide yes)
			(effects
				(font
					(size 1.27 1.27)
				)
			)
		)
		(property "Value" "AO4407AL-GP"
			(at -3.707384 -1.5367 0)
			(unlocked yes)
			(layer "F.Fab")
			(hide yes)
			(effects
				(font
					(size 1.016 1.016)
					(thickness 0.1524)
				)
			)
		)
		(property "Device Type" "SOIC8H69"
			(at -3.707384 -3.0607 0)
			(unlocked yes)
			(layer "F.Fab")
			(hide yes)
			(effects
				(font
					(size 1.016 1.016)
					(thickness 0.1524)
				)
			)
		)
		(duplicate_pad_numbers_are_jumpers no)
		(fp_line
			(start -2.7432 -1.4224)
			(end -2.7432 1.4224)
			(stroke
				(width 0.1524)
				(type default)
			)
			(layer "F.SilkS")
		)
		(fp_line
			(start -2.7432 1.4224)
			(end -2.6416 1.4224)
			(stroke
				(width 0.1524)
				(type default)
			)
			(layer "F.SilkS")
		)
		(fp_line
			(start -2.7432 1.4224)
			(end 2.1336 1.4224)
			(stroke
				(width 0.1524)
				(type default)
			)
			(layer "F.SilkS")
		)
		(fp_line
			(start -2.7178 -0.508)
			(end -2.1844 -0.0508)
			(stroke
				(width 0.1524)
				(type default)
			)
			(layer "F.SilkS")
		)
		(fp_line
			(start -2.6289 3.4417)
			(end -2.6289 1.4732)
			(stroke
				(width 0.381)
				(type default)
			)
			(layer "F.SilkS")
		)
		(fp_line
			(start -2.1844 -0.0508)
			(end -2.7178 0.508)
			(stroke
				(width 0.1524)
				(type default)
			)
			(layer "F.SilkS")
		)
		(fp_line
			(start 2.1336 -1.4224)
			(end -2.7432 -1.4224)
			(stroke
				(width 0.1524)
				(type default)
			)
			(layer "F.SilkS")
		)
		(fp_line
			(start 2.1336 1.4224)
			(end 2.1336 -1.4224)
			(stroke
				(width 0.1524)
				(type default)
			)
			(layer "F.SilkS")
		)
		(fp_poly
			(pts
				(xy -2.2098 -1.4224) (xy -2.2098 1.4224) (xy 2.2098 1.4224) (xy 2.2098 -1.4224)
			)
			(stroke
				(width 0)
				(type default)
			)
			(fill yes)
			(layer "F.SilkS")
		)
		(fp_rect
			(start -2.450084 2.999994)
			(end 2.450084 -2.999994)
			(stroke
				(width 0)
				(type default)
			)
			(fill no)
			(layer "F.CrtYd")
		)
		(fp_poly
			(pts
				(xy -2.8194 3.6322) (xy -2.8194 -3.6322) (xy 2.8194 -3.6322) (xy 2.8194 1.18364) (xy 2.450084 1.18364)
				(xy 2.450084 -2.999994) (xy -2.450084 -2.999994) (xy -2.450084 2.999994) (xy 2.450084 2.999994)
				(xy 2.450084 1.18618) (xy 2.8194 1.18618) (xy 2.8194 3.6322)
			)
			(stroke
				(width 0)
				(type default)
			)
			(fill no)
			(layer "F.CrtYd")
		)
		(fp_rect
			(start -2.8194 3.6322)
			(end 2.8194 -3.6322)
			(stroke
				(width 0)
				(type default)
			)
			(fill no)
			(layer "F.Fab")
		)
		(pad "1" smd rect
			(at -1.905 2.54)
			(size 0.635 1.651)
			(layers "F.Cu" "F.Mask" "F.Paste")
			(net "P12V_B")
		)
		(pad "2" smd rect
			(at -0.635 2.54)
			(size 0.635 1.651)
			(layers "F.Cu" "F.Mask" "F.Paste")
			(net "P12V_B")
		)
		(pad "3" smd rect
			(at 0.635 2.54)
			(size 0.635 1.651)
			(layers "F.Cu" "F.Mask" "F.Paste")
			(net "P12V_B")
		)
		(pad "4" smd rect
			(at 1.905 2.54)
			(size 0.635 1.651)
			(layers "F.Cu" "F.Mask" "F.Paste")
			(net "SW_HDD_N9")
		)
		(pad "5" smd rect
			(at 1.905 -2.54)
			(size 0.635 1.651)
			(layers "F.Cu" "F.Mask" "F.Paste")
			(net "P12V_HDD9")
		)
		(pad "6" smd rect
			(at 0.635 -2.54)
			(size 0.635 1.651)
			(layers "F.Cu" "F.Mask" "F.Paste")
			(net "P12V_HDD9")
		)
		(pad "7" smd rect
			(at -0.635 -2.54)
			(size 0.635 1.651)
			(layers "F.Cu" "F.Mask" "F.Paste")
			(net "P12V_HDD9")
		)
		(pad "8" smd rect
			(at -1.905 -2.54)
			(size 0.635 1.651)
			(layers "F.Cu" "F.Mask" "F.Paste")
			(net "P12V_HDD9")
		)
	)
)
